# TIMECARD (Time Appliance Project (Time Card)) — schematic netlist excerpt (pin names and nets, part order shuffled) for the footprints in the layout excerpt that follows; sources: Cadence DE-HDL packaged netlist, KiCad conversion of R4006-B0001-02_R01.brd

C14  CAPACITOR  22UF 10V 20%  pkg SMC_0805R_H057  page 32 : \1\ = XP5R0V ; \2\ = SG
C275  CAPACITOR  0.1UF 25V 10%  pkg SMC_0402R_H022  page 18 : \1\ = VDD3V3_SHT31A ; \2\ = SG

(kicad_pcb
	(version 20260206)
	(generator "pcbnew")
	(generator_version "10.0")
	(general
		(thickness 1.6)
		(legacy_teardrops no)
	)
	(paper "A4")
	(title_block
		(title "timecard-production-celestica-r4006 — R4006-B0001-02_R01.brd")
		(comment 1 "Time Appliance Project (Time Card) / footprints 289-290 of 1113")
	)
	(layers
		(0 "F.Cu" signal "TOP")
		(4 "In1.Cu" signal "L02_GND1")
		(6 "In2.Cu" signal "L03_SIG1")
		(8 "In3.Cu" signal "L04_GND2")
		(10 "In4.Cu" signal "L05_VCC1")
		(12 "In5.Cu" signal "L06_VCC2")
		(14 "In6.Cu" signal "L07_GND3")
		(16 "In7.Cu" signal "L08_SIG2")
		(18 "In8.Cu" signal "L09_GND4")
		(2 "B.Cu" signal "BOTTOM")
		(9 "F.Adhes" user "F.Adhesive")
		(11 "B.Adhes" user "B.Adhesive")
		(13 "F.Paste" user "Package Geometry/Pastemask Top")
		(15 "B.Paste" user "Package Geometry/Pastemask Bottom")
		(5 "F.SilkS" user "Ref Des/Silkscreen Top")
		(7 "B.SilkS" user "Ref Des/Silkscreen Bottom")
		(1 "F.Mask" user "Board Geometry/Soldermask Top")
		(3 "B.Mask" user "Board Geometry/Soldermask Bottom")
		(17 "Dwgs.User" user "User.Drawings")
		(19 "Cmts.User" user "User.Comments")
		(21 "Eco1.User" user "User.Eco1")
		(23 "Eco2.User" user "User.Eco2")
		(25 "Edge.Cuts" user "Board Geometry/Outline")
		(27 "Margin" user)
		(31 "F.CrtYd" user "Package Geometry/Place Bound Top")
		(29 "B.CrtYd" user "Package Geometry/Place Bound Bottom")
		(35 "F.Fab" user "Ref Des/Assembly Top")
		(33 "B.Fab" user "Ref Des/Assembly Bottom")
	)
	(footprint ""
		(layer "F.Cu")
		(at 55.5244 -103.4034 90)
		(property "Reference" "C14"
			(at 0 3.84937 90)
			(unlocked yes)
			(layer "F.SilkS")
			(effects
				(font
					(size 0.7874 0.5842)
					(thickness 0.1524)
				)
			)
		)
		(property "Value" "VAL*"
			(at 0.0762 3.134106 90)
			(unlocked yes)
			(layer "F.Fab")
			(hide yes)
			(effects
				(font
					(size 0.7874 0.5842)
					(thickness 0.1524)
				)
			)
		)
		(property "Device Type" "CAPACITOR-G107-0F226-CM,22UF,2A"
			(at 0.0508 2.194306 90)
			(unlocked yes)
			(layer "F.Fab")
			(hide yes)
			(effects
				(font
					(size 0.7874 0.5842)
					(thickness 0.1524)
				)
			)
		)
		(property "User Part Number" "PARTNUM*"
			(at 0.1016 5.013706 90)
			(unlocked yes)
			(layer "Cmts.User")
			(hide yes)
			(effects
				(font
					(size 0.7874 0.5842)
					(thickness 0.1524)
				)
			)
		)
		(property "Tolerance" "TOL*"
			(at 0.0762 4.048506 90)
			(unlocked yes)
			(layer "Cmts.User")
			(hide yes)
			(effects
				(font
					(size 0.7874 0.5842)
					(thickness 0.1524)
				)
			)
		)
		(duplicate_pad_numbers_are_jumpers no)
		(fp_line
			(start 1.5748 -0.9398)
			(end -1.5748 -0.9398)
			(stroke
				(width 0.1)
				(type default)
			)
			(layer "F.SilkS")
		)
		(fp_line
			(start -1.5748 -0.9398)
			(end -1.5748 0.9398)
			(stroke
				(width 0.1)
				(type default)
			)
			(layer "F.SilkS")
		)
		(fp_line
			(start 1.5748 0.9398)
			(end 1.5748 -0.9398)
			(stroke
				(width 0.1)
				(type default)
			)
			(layer "F.SilkS")
		)
		(fp_line
			(start -1.5748 0.9398)
			(end 1.5748 0.9398)
			(stroke
				(width 0.1)
				(type default)
			)
			(layer "F.SilkS")
		)
		(fp_rect
			(start 1.5748 0.9398)
			(end -1.5748 -0.9398)
			(stroke
				(width 0)
				(type default)
			)
			(fill no)
			(layer "F.CrtYd")
		)
		(fp_line
			(start 1.016 -0.635)
			(end -1.016 -0.635)
			(stroke
				(width 0.1)
				(type default)
			)
			(layer "F.Fab")
		)
		(fp_line
			(start -1.016 -0.635)
			(end -1.016 0.635)
			(stroke
				(width 0.1)
				(type default)
			)
			(layer "F.Fab")
		)
		(fp_line
			(start 1.016 0.635)
			(end 1.016 -0.635)
			(stroke
				(width 0.1)
				(type default)
			)
			(layer "F.Fab")
		)
		(fp_line
			(start -1.016 0.635)
			(end 1.016 0.635)
			(stroke
				(width 0.1)
				(type default)
			)
			(layer "F.Fab")
		)
		(pad "1" smd rect
			(at -0.8382 0 90)
			(size 0.9652 1.3716)
			(layers "F.Cu" "F.Mask" "F.Paste")
			(net "XP5R0V")
		)
		(pad "2" smd rect
			(at 0.8382 0 90)
			(size 0.9652 1.3716)
			(layers "F.Cu" "F.Mask" "F.Paste")
			(net "SG")
		)
		(zone
			(layer "F.Cu")
			(hatch none 0.5)
			(connect_pads
				(clearance 0)
			)
			(min_thickness 0.25)
			(keepout
				(tracks allowed)
				(vias not_allowed)
				(pads allowed)
				(copperpour not_allowed)
				(footprints allowed)
			)
			(placement
				(enabled no)
				(sheetname "")
			)
			(fill
				(thermal_gap 0.5)
				(thermal_bridge_width 0.5)
				(island_removal_mode 0)
			)
			(polygon
				(pts
					(xy 56.1594 -103.632) (xy 54.8894 -103.632) (xy 54.8894 -103.1748) (xy 56.1594 -103.1748)
				)
			)
		)
	)
	(footprint ""
		(layer "F.Cu")
		(at 153.67 -57.658)
		(property "Reference" "C275"
			(at 1.905 2.32537 0)
			(unlocked yes)
			(layer "F.SilkS")
			(effects
				(font
					(size 0.7874 0.5842)
					(thickness 0.1524)
				)
			)
		)
		(property "Value" "VAL*"
			(at 0.0762 2.067306 0)
			(unlocked yes)
			(layer "F.Fab")
			(hide yes)
			(effects
				(font
					(size 0.7874 0.5842)
					(thickness 0.1524)
				)
			)
		)
		(property "Tolerance" "TOL*"
			(at 0.0762 3.032506 0)
			(unlocked yes)
			(layer "Cmts.User")
			(hide yes)
			(effects
				(font
					(size 0.7874 0.5842)
					(thickness 0.1524)
				)
			)
		)
		(property "User Part Number" "PARTNUM*"
			(at 0.1016 4.023106 0)
			(unlocked yes)
			(layer "Cmts.User")
			(hide yes)
			(effects
				(font
					(size 0.7874 0.5842)
					(thickness 0.1524)
				)
			)
		)
		(property "Device Type" "CAPACITOR-G105-0B104-EK,0.1UF,A"
			(at 0.0508 1.127506 0)
			(unlocked yes)
			(layer "F.Fab")
			(hide yes)
			(effects
				(font
					(size 0.7874 0.5842)
					(thickness 0.1524)
				)
			)
		)
		(duplicate_pad_numbers_are_jumpers no)
		(fp_line
			(start -1.143 -0.5588)
			(end -1.143 0.5588)
			(stroke
				(width 0.1)
				(type default)
			)
			(layer "F.SilkS")
		)
		(fp_line
			(start -1.143 0.5588)
			(end 1.143 0.5588)
			(stroke
				(width 0.1)
				(type default)
			)
			(layer "F.SilkS")
		)
		(fp_line
			(start 1.143 -0.5588)
			(end -1.143 -0.5588)
			(stroke
				(width 0.1)
				(type default)
			)
			(layer "F.SilkS")
		)
		(fp_line
			(start 1.143 0.5588)
			(end 1.143 -0.5588)
			(stroke
				(width 0.1)
				(type default)
			)
			(layer "F.SilkS")
		)
		(fp_rect
			(start 1.143 -0.5588)
			(end -1.143 0.5588)
			(stroke
				(width 0)
				(type default)
			)
			(fill no)
			(layer "F.CrtYd")
		)
		(fp_line
			(start -0.508 -0.3048)
			(end -0.508 0.3048)
			(stroke
				(width 0.1)
				(type default)
			)
			(layer "F.Fab")
		)
		(fp_line
			(start -0.508 0.3048)
			(end 0.508 0.3048)
			(stroke
				(width 0.1)
				(type default)
			)
			(layer "F.Fab")
		)
		(fp_line
			(start 0.508 -0.3048)
			(end -0.508 -0.3048)
			(stroke
				(width 0.1)
				(type default)
			)
			(layer "F.Fab")
		)
		(fp_line
			(start 0.508 0.3048)
			(end 0.508 -0.3048)
			(stroke
				(width 0.1)
				(type default)
			)
			(layer "F.Fab")
		)
		(pad "1" smd rect
			(at -0.5334 0)
			(size 0.7112 0.6096)
			(layers "F.Cu" "F.Mask" "F.Paste")
			(net "VDD3V3_SHT31A")
		)
		(pad "2" smd rect
			(at 0.5334 0)
			(size 0.7112 0.6096)
			(layers "F.Cu" "F.Mask" "F.Paste")
			(net "SG")
		)
		(zone
			(layer "F.Cu")
			(hatch none 0.5)
			(connect_pads
				(clearance 0)
			)
			(min_thickness 0.25)
			(keepout
				(tracks allowed)
				(vias not_allowed)
				(pads allowed)
				(copperpour not_allowed)
				(footprints allowed)
			)
			(placement
				(enabled no)
				(sheetname "")
			)
			(fill
				(thermal_gap 0.5)
				(thermal_bridge_width 0.5)
				(island_removal_mode 0)
			)
			(polygon
				(pts
					(xy 153.7462 -57.9628) (xy 153.5938 -57.9628) (xy 153.5938 -57.3532) (xy 153.7462 -57.3532)
				)
			)
		)
	)
)
